FILE_TYPE=LIBRARY_PARTS;
primitive 'RT8240','RT8240_QFN';
  pin
    'BOOT':
      PIN_NUMBER='(4)';
      INPUT_LOAD='(-0.01,0.01)';
    'CS':
      PIN_NUMBER='(10)';
      INPUT_LOAD='(-0.01,0.01)';
    'EN':
      PIN_NUMBER='(8)';
      INPUT_LOAD='(-0.01,0.01)';
    'G0':
      PIN_NUMBER='(11)';
      INPUT_LOAD='(-0.01,0.01)';
    'GND'<1>:
      PIN_NUMBER='(13)';
      PINUSE='GROUND';
      NO_LOAD_CHECK='Both';
      NO_IO_CHECK='Both';
      NO_ASSERT_CHECK='TRUE';
      NO_DIR_CHECK='TRUE';
      ALLOW_CONNECT='TRUE';
    'GND'<0>:
      PIN_NUMBER='(12)';
      PINUSE='GROUND';
      NO_LOAD_CHECK='Both';
      NO_IO_CHECK='Both';
      NO_ASSERT_CHECK='TRUE';
      NO_DIR_CHECK='TRUE';
      ALLOW_CONNECT='TRUE';
    'LGATE':
      PIN_NUMBER='(1)';
      OUTPUT_LOAD='(1.0,-1.0)';
    'PGOOD':
      PIN_NUMBER='(9)';
      INPUT_LOAD='(-0.01,0.01)';
    'PHASE':
      PIN_NUMBER='(2)';
      INPUT_LOAD='(-0.01,0.01)';
    'RGND':
      PIN_NUMBER='(7)';
      PINUSE='GROUND';
      NO_LOAD_CHECK='Both';
      NO_IO_CHECK='Both';
      NO_ASSERT_CHECK='TRUE';
      NO_DIR_CHECK='TRUE';
      ALLOW_CONNECT='TRUE';
    'UGATE':
      PIN_NUMBER='(3)';
      OUTPUT_LOAD='(1.0,-1.0)';
    'VCC':
      PIN_NUMBER='(5)';
      PINUSE='POWER';
      NO_LOAD_CHECK='Both';
      NO_IO_CHECK='Both';
      NO_ASSERT_CHECK='TRUE';
      NO_DIR_CHECK='TRUE';
      ALLOW_CONNECT='TRUE';
    'VOUT':
      PIN_NUMBER='(6)';
      OUTPUT_LOAD='(1.0,-1.0)';
  end_pin;
  body
    PART_NAME='RT8240';
    PHYS_DES_PREFIX='EU';
  end_body;
end_primitive;

END.
